# S9S_MB_2U (Grand Teton) — schematic netlist excerpt (pin names and nets, part order shuffled) for the footprints in the layout excerpt that follows; sources: Cadence DE-HDL packaged netlist, KiCad conversion of 03242023_DA0F0TMBIJ0_F0T_Motherboard_J_brd_V01_OCP.brd

R4180  Q_RES  33.2 1% CHIP  pkg 0402LF  page 170 : A = SMB_LM75_0_3V3AUX_SCL ; B = SMB_LM75_0_3V3AUX_SCL_R1
PC602_P0_1  Q_CAP  3300PF 50V 10% X7R  pkg 0402  page 271 : A = SW_P12V_PVCCFA_EHV_FIVRA_CPU0_R ; B = GND

(kicad_pcb
	(version 20260206)
	(generator "pcbnew")
	(generator_version "10.0")
	(general
		(thickness 1.6)
		(legacy_teardrops no)
	)
	(paper "A4")
	(title_block
		(title "03242023_DA0F0TMBIJ0_F0T_Motherboard_J_brd_V01_OCP.brd")
		(comment 1 "Grand Teton / footprints 3344-3345 of 6105")
	)
	(layers
		(0 "F.Cu" signal "TOP")
		(4 "In1.Cu" signal "GND")
		(6 "In2.Cu" signal "IN1")
		(8 "In3.Cu" signal "GND1")
		(10 "In4.Cu" signal "IN2")
		(12 "In5.Cu" signal "GND2")
		(14 "In6.Cu" signal "IN3")
		(16 "In7.Cu" signal "GND3")
		(18 "In8.Cu" signal "VCC")
		(20 "In9.Cu" signal "VCC1")
		(22 "In10.Cu" signal "GND4")
		(24 "In11.Cu" signal "IN4")
		(26 "In12.Cu" signal "GND5")
		(28 "In13.Cu" signal "IN5")
		(30 "In14.Cu" signal "GND6")
		(32 "In15.Cu" signal "IN6")
		(34 "In16.Cu" signal "GND7")
		(2 "B.Cu" signal "BOTTOM")
		(9 "F.Adhes" user "F.Adhesive")
		(11 "B.Adhes" user "B.Adhesive")
		(13 "F.Paste" user "Package Geometry/Pastemask Top")
		(15 "B.Paste" user "Package Geometry/Pastemask Bottom")
		(5 "F.SilkS" user "Ref Des/Silkscreen Top")
		(7 "B.SilkS" user "Ref Des/Silkscreen Bottom")
		(1 "F.Mask" user "Board Geometry/Soldermask Top")
		(3 "B.Mask" user "Board Geometry/Soldermask Bottom")
		(17 "Dwgs.User" user "User.Drawings")
		(19 "Cmts.User" user "User.Comments")
		(21 "Eco1.User" user "User.Eco1")
		(23 "Eco2.User" user "User.Eco2")
		(25 "Edge.Cuts" user "Board Geometry/Outline")
		(27 "Margin" user)
		(31 "F.CrtYd" user "Package Geometry/Place Bound Top")
		(29 "B.CrtYd" user "Package Geometry/Place Bound Bottom")
		(35 "F.Fab" user "Ref Des/Assembly Top")
		(33 "B.Fab" user "Ref Des/Assembly Bottom")
	)
	(footprint ""
		(layer "F.Cu")
		(at 420.774114 -362.155994 -90)
		(property "Reference" "PC602_P0_1"
			(at 0 0 270)
			(layer "F.SilkS")
			(hide yes)
			(effects
				(font
					(size 1.27 1.27)
				)
			)
		)
		(property "Value" ""
			(at 0 0 270)
			(layer "F.Fab")
			(effects
				(font
					(size 1.27 1.27)
				)
			)
		)
		(duplicate_pad_numbers_are_jumpers no)
		(fp_line
			(start -0.7874 0.4064)
			(end -0.7874 -0.4064)
			(stroke
				(width 0.1524)
				(type default)
			)
			(layer "F.SilkS")
		)
		(fp_line
			(start 0.7874 0.4064)
			(end -0.7874 0.4064)
			(stroke
				(width 0.1524)
				(type default)
			)
			(layer "F.SilkS")
		)
		(fp_line
			(start -0.7874 -0.4064)
			(end 0.7874 -0.4064)
			(stroke
				(width 0.1524)
				(type default)
			)
			(layer "F.SilkS")
		)
		(fp_line
			(start 0.7874 -0.4064)
			(end 0.7874 0.4064)
			(stroke
				(width 0.1524)
				(type default)
			)
			(layer "F.SilkS")
		)
		(fp_line
			(start -0.67945 0.3048)
			(end -0.67945 -0.305054)
			(stroke
				(width 0.1)
				(type default)
			)
			(layer "F.Fab")
		)
		(fp_line
			(start -0.12065 0.3048)
			(end -0.67945 0.3048)
			(stroke
				(width 0.1)
				(type default)
			)
			(layer "F.Fab")
		)
		(fp_line
			(start 0.120396 0.3048)
			(end 0.120396 0.2794)
			(stroke
				(width 0.1)
				(type default)
			)
			(layer "F.Fab")
		)
		(fp_line
			(start 0.67945 0.3048)
			(end 0.120396 0.3048)
			(stroke
				(width 0.1)
				(type default)
			)
			(layer "F.Fab")
		)
		(fp_line
			(start -0.12065 0.2794)
			(end -0.12065 0.3048)
			(stroke
				(width 0.1)
				(type default)
			)
			(layer "F.Fab")
		)
		(fp_line
			(start 0.120396 0.2794)
			(end -0.12065 0.2794)
			(stroke
				(width 0.1)
				(type default)
			)
			(layer "F.Fab")
		)
		(fp_line
			(start -0.12065 -0.2794)
			(end 0.12065 -0.2794)
			(stroke
				(width 0.1)
				(type default)
			)
			(layer "F.Fab")
		)
		(fp_line
			(start 0.12065 -0.2794)
			(end 0.12065 -0.3048)
			(stroke
				(width 0.1)
				(type default)
			)
			(layer "F.Fab")
		)
		(fp_line
			(start 0.12065 -0.3048)
			(end 0.67945 -0.3048)
			(stroke
				(width 0.1)
				(type default)
			)
			(layer "F.Fab")
		)
		(fp_line
			(start 0.67945 -0.3048)
			(end 0.67945 0.3048)
			(stroke
				(width 0.1)
				(type default)
			)
			(layer "F.Fab")
		)
		(fp_line
			(start -0.67945 -0.305054)
			(end -0.12065 -0.305054)
			(stroke
				(width 0.1)
				(type default)
			)
			(layer "F.Fab")
		)
		(fp_line
			(start -0.12065 -0.305054)
			(end -0.12065 -0.2794)
			(stroke
				(width 0.1)
				(type default)
			)
			(layer "F.Fab")
		)
		(pad "1" smd circle
			(at -0.40005 0 270)
			(size 0 0)
			(layers "F.Cu" "F.Mask" "F.Paste")
			(net "SW_P12V_PVCCFA_EHV_FIVRA_CPU0_R")
		)
		(pad "2" smd circle
			(at 0.40005 0 270)
			(size 0 0)
			(layers "F.Cu" "F.Mask" "F.Paste")
			(net "GND")
		)
	)
	(footprint ""
		(layer "F.Cu")
		(at 366.432338 -424.085766)
		(property "Reference" "R4180"
			(at 0 0 0)
			(layer "F.SilkS")
			(hide yes)
			(effects
				(font
					(size 1.27 1.27)
				)
			)
		)
		(property "Value" ""
			(at 0 0 0)
			(layer "F.Fab")
			(effects
				(font
					(size 1.27 1.27)
				)
			)
		)
		(duplicate_pad_numbers_are_jumpers no)
		(fp_line
			(start -0.7874 -0.4064)
			(end 0.7874 -0.4064)
			(stroke
				(width 0.1524)
				(type default)
			)
			(layer "F.SilkS")
		)
		(fp_line
			(start -0.7874 0.4064)
			(end -0.7874 -0.4064)
			(stroke
				(width 0.1524)
				(type default)
			)
			(layer "F.SilkS")
		)
		(fp_line
			(start 0.7874 -0.4064)
			(end 0.7874 0.4064)
			(stroke
				(width 0.1524)
				(type default)
			)
			(layer "F.SilkS")
		)
		(fp_line
			(start 0.7874 0.4064)
			(end -0.7874 0.4064)
			(stroke
				(width 0.1524)
				(type default)
			)
			(layer "F.SilkS")
		)
		(fp_line
			(start -0.67945 -0.305054)
			(end -0.12065 -0.305054)
			(stroke
				(width 0.1)
				(type default)
			)
			(layer "F.Fab")
		)
		(fp_line
			(start -0.67945 0.3048)
			(end -0.67945 -0.305054)
			(stroke
				(width 0.1)
				(type default)
			)
			(layer "F.Fab")
		)
		(fp_line
			(start -0.12065 -0.305054)
			(end -0.12065 -0.2794)
			(stroke
				(width 0.1)
				(type default)
			)
			(layer "F.Fab")
		)
		(fp_line
			(start -0.12065 -0.2794)
			(end 0.12065 -0.2794)
			(stroke
				(width 0.1)
				(type default)
			)
			(layer "F.Fab")
		)
		(fp_line
			(start -0.12065 0.2794)
			(end -0.12065 0.3048)
			(stroke
				(width 0.1)
				(type default)
			)
			(layer "F.Fab")
		)
		(fp_line
			(start -0.12065 0.3048)
			(end -0.67945 0.3048)
			(stroke
				(width 0.1)
				(type default)
			)
			(layer "F.Fab")
		)
		(fp_line
			(start 0.120396 0.2794)
			(end -0.12065 0.2794)
			(stroke
				(width 0.1)
				(type default)
			)
			(layer "F.Fab")
		)
		(fp_line
			(start 0.120396 0.3048)
			(end 0.120396 0.2794)
			(stroke
				(width 0.1)
				(type default)
			)
			(layer "F.Fab")
		)
		(fp_line
			(start 0.12065 -0.3048)
			(end 0.67945 -0.3048)
			(stroke
				(width 0.1)
				(type default)
			)
			(layer "F.Fab")
		)
		(fp_line
			(start 0.12065 -0.2794)
			(end 0.12065 -0.3048)
			(stroke
				(width 0.1)
				(type default)
			)
			(layer "F.Fab")
		)
		(fp_line
			(start 0.67945 -0.3048)
			(end 0.67945 0.3048)
			(stroke
				(width 0.1)
				(type default)
			)
			(layer "F.Fab")
		)
		(fp_line
			(start 0.67945 0.3048)
			(end 0.120396 0.3048)
			(stroke
				(width 0.1)
				(type default)
			)
			(layer "F.Fab")
		)
		(pad "1" smd circle
			(at -0.40005 0)
			(size 0 0)
			(layers "F.Cu" "F.Mask" "F.Paste")
			(net "SMB_LM75_0_3V3AUX_SCL")
		)
		(pad "2" smd circle
			(at 0.40005 0)
			(size 0 0)
			(layers "F.Cu" "F.Mask" "F.Paste")
			(net "SMB_LM75_0_3V3AUX_SCL_R1")
		)
	)
)
